# T6G (Grand Teton) — schematic netlist excerpt (pin names and nets, part order shuffled) for the footprints in the layout excerpt that follows; sources: Cadence DE-HDL packaged netlist, KiCad conversion of 04192023_DAF0TMB3IC0_F0TG_MB_C_brd_V02_OCP.brd

J59  SCONN75K_APCI0155P004A  SCONN75K_APCI0155-P004A EMPTY  pkg CON_F67S2H2D2S_P0-5W7-55_LUVXB_H270  page 144
  GND1  = PCIE_M2_SSD0_PRSNT_N
  \3.3v_1\  = P3V3_M2_0
  GND2  = GND
  \3.3v_2\  = P3V3_M2_0
  PERN3  = P3E_CPU1_P4_RX_DN<3>
  NC1  = NC_M2_0_NC1
  PERP3  = P3E_CPU1_P4_RX_DP<3>
  NC2  = NC_M2_0_NC2
  GND3  = GND
  \das_dss#||led1#\  = LED_M2_SSD_0_ACT_N
  PETN3  = P3E_CPU1_P4_TX_C_DN<3>
  \3.3v_3\  = P3V3_M2_0
  PETP3  = P3E_CPU1_P4_TX_C_DP<3>
  \3.3v_4\  = P3V3_M2_0
  GND4  = GND
  \3.3v_5\  = P3V3_M2_0
  PERN2  = P3E_CPU1_P4_RX_DN<2>
  \3.3v_6\  = P3V3_M2_0
  PERP2  = P3E_CPU1_P4_RX_DP<2>
  NC3  = NC_M2_0_NC3
  GND5  = GND
  NC4  = NC_M2_0_NC4
  PETN2  = P3E_CPU1_P4_TX_C_DN<2>
  NC5  = NC_M2_0_NC5
  PETP2  = P3E_CPU1_P4_TX_C_DP<2>
  NC6  = NC_M2_0_NC6
  GND6  = GND
  NC7  = NC_M2_0_NC7
  PERN1  = P3E_CPU1_P4_RX_DN<1>
  NC8  = NC_M2_0_NC8
  PERP1  = P3E_CPU1_P4_RX_DP<1>
  NC9  = NC_M2_0_NC9
  GND7  = GND
  NC10  = NC_M2_0_NC10
  PETN1  = P3E_CPU1_P4_TX_C_DN<1>
  NC11  = NC_M2_0_NC11
  PETP1  = P3E_CPU1_P4_TX_C_DP<1>
  DEVSLP  = PD_M2_0_DEVSLP
  GND8  = GND
  NC12  = SMB_M2_P1_1V8AUX_SCL
  \pern0||sata-b+\  = P3E_CPU1_P4_RX_DN<0>
  NC13  = SMB_M2_P1_1V8AUX_SDA
  \perp0||sata-b-\  = P3E_CPU1_P4_RX_DP<0>
  NC14  = NC_M2_0_NC14
  GND9  = GND
  NC15  = NC_M2_0_NC15
  \petn0||sata-a-\  = P3E_CPU1_P4_TX_C_DN<0>
  NC16  = NC_M2_0_NC16
  \petp0||sata-a+\  = P3E_CPU1_P4_TX_C_DP<0>
  \perst#\  = RST_PERST_BUF_M2_0_R_N
  GND10  = GND
  \clkreq#\  = M2_SSD0_CLKREQ_EN_N_BUF
  REFCLKN  = CLK_100M_CPU1_CLK12_DN
  \pewake#\  = M2_0_PEWAKE_N
  REFCLKP  = CLK_100M_CPU1_CLK12_DP
  NC17  = NC_M2_0_NC17
  GND11  = GND
  NC18  = NC_M2_0_NC18
  NC19  = NC_M2_0_NC19
  SUSCLK  = NC_M2_0_SUSCLK
  PEDET  = FM_M2_SSD_0_PEDET
  \3.3v_7\  = P3V3_M2_0
  GND12  = GND
  \3.3v_8\  = P3V3_M2_0
  GND13  = GND
  \3.3v_9\  = P3V3_M2_0
  GND14  = GND
  G1  = GND
  G2  = GND

(kicad_pcb
	(version 20260206)
	(generator "pcbnew")
	(generator_version "10.0")
	(general
		(thickness 1.6)
		(legacy_teardrops no)
	)
	(paper "A4")
	(title_block
		(title "04192023_DAF0TMB3IC0_F0TG_MB_C_brd_V02_OCP.brd")
		(comment 1 "Grand Teton / footprint 1180 of 8354 (J59), pads 45-71 of 71")
	)
	(layers
		(0 "F.Cu" signal "TOP")
		(4 "In1.Cu" signal "GND")
		(6 "In2.Cu" signal "IN1")
		(8 "In3.Cu" signal "GND1")
		(10 "In4.Cu" signal "IN2")
		(12 "In5.Cu" signal "GND2")
		(14 "In6.Cu" signal "IN3")
		(16 "In7.Cu" signal "GND3")
		(18 "In8.Cu" signal "VCC")
		(20 "In9.Cu" signal "VCC1")
		(22 "In10.Cu" signal "GND4")
		(24 "In11.Cu" signal "IN4")
		(26 "In12.Cu" signal "GND5")
		(28 "In13.Cu" signal "IN5")
		(30 "In14.Cu" signal "GND6")
		(32 "In15.Cu" signal "IN6")
		(34 "In16.Cu" signal "GND7")
		(2 "B.Cu" signal "BOTTOM")
		(9 "F.Adhes" user "F.Adhesive")
		(11 "B.Adhes" user "B.Adhesive")
		(13 "F.Paste" user "Package Geometry/Pastemask Top")
		(15 "B.Paste" user "Package Geometry/Pastemask Bottom")
		(5 "F.SilkS" user "Ref Des/Silkscreen Top")
		(7 "B.SilkS" user "Ref Des/Silkscreen Bottom")
		(1 "F.Mask" user "Board Geometry/Soldermask Top")
		(3 "B.Mask" user "Board Geometry/Soldermask Bottom")
		(17 "Dwgs.User" user "User.Drawings")
		(19 "Cmts.User" user "User.Comments")
		(21 "Eco1.User" user "User.Eco1")
		(23 "Eco2.User" user "User.Eco2")
		(25 "Edge.Cuts" user "Board Geometry/Outline")
		(27 "Margin" user)
		(31 "F.CrtYd" user "Package Geometry/Place Bound Top")
		(29 "B.CrtYd" user "Package Geometry/Place Bound Bottom")
		(35 "F.Fab" user "Ref Des/Assembly Top")
		(33 "B.Fab" user "Ref Des/Assembly Bottom")
	)
	(footprint ""
		(layer "F.Cu")
		(at 173.358302 -47.049944)
		(property "Reference" "J59"
			(at -4.4958 -11.852148 0)
			(unlocked yes)
			(layer "F.SilkS")
			(effects
				(font
					(size 0.7874 0.5842)
					(thickness 0.1524)
				)
				(justify left)
			)
		)
		(property "Value" ""
			(at 0 0 0)
			(layer "F.Fab")
			(effects
				(font
					(size 1.27 1.27)
				)
			)
		)
		(duplicate_pad_numbers_are_jumpers no)
		(pad "43" smd rect
			(at 3.750056 1.249934 270)
			(size 0.2794 1.6002)
			(layers "F.Cu" "F.Mask" "F.Paste")
			(net "P3E_CPU1_P4_RX_DP<0>")
		)
		(pad "44" smd rect
			(at -3.800094 1.500124 270)
			(size 0.2794 1.6002)
			(layers "F.Cu" "F.Mask" "F.Paste")
			(net "NC_M2_0_NC14")
		)
		(pad "45" smd rect
			(at 3.750056 1.75006 270)
			(size 0.2794 1.6002)
			(layers "F.Cu" "F.Mask" "F.Paste")
			(net "GND")
		)
		(pad "46" smd rect
			(at -3.800094 1.999996 270)
			(size 0.2794 1.6002)
			(layers "F.Cu" "F.Mask" "F.Paste")
			(net "NC_M2_0_NC15")
		)
		(pad "47" smd rect
			(at 3.750056 2.249932 270)
			(size 0.2794 1.6002)
			(layers "F.Cu" "F.Mask" "F.Paste")
			(net "P3E_CPU1_P4_TX_C_DN<0>")
		)
		(pad "48" smd rect
			(at -3.800094 2.500122 270)
			(size 0.2794 1.6002)
			(layers "F.Cu" "F.Mask" "F.Paste")
			(net "NC_M2_0_NC16")
		)
		(pad "49" smd rect
			(at 3.750056 2.750058 270)
			(size 0.2794 1.6002)
			(layers "F.Cu" "F.Mask" "F.Paste")
			(net "P3E_CPU1_P4_TX_C_DP<0>")
		)
		(pad "50" smd rect
			(at -3.800094 2.999994 270)
			(size 0.2794 1.6002)
			(layers "F.Cu" "F.Mask" "F.Paste")
			(net "RST_PERST_BUF_M2_0_R_N")
		)
		(pad "51" smd rect
			(at 3.750056 3.24993 270)
			(size 0.2794 1.6002)
			(layers "F.Cu" "F.Mask" "F.Paste")
			(net "GND")
		)
		(pad "52" smd rect
			(at -3.800094 3.50012 270)
			(size 0.2794 1.6002)
			(layers "F.Cu" "F.Mask" "F.Paste")
			(net "M2_SSD0_CLKREQ_EN_N_BUF")
		)
		(pad "53" smd rect
			(at 3.750056 3.750056 270)
			(size 0.2794 1.6002)
			(layers "F.Cu" "F.Mask" "F.Paste")
			(net "CLK_100M_CPU1_CLK12_DN")
		)
		(pad "54" smd rect
			(at -3.800094 3.999992 270)
			(size 0.2794 1.6002)
			(layers "F.Cu" "F.Mask" "F.Paste")
			(net "M2_0_PEWAKE_N")
		)
		(pad "55" smd rect
			(at 3.750056 4.249928 270)
			(size 0.2794 1.6002)
			(layers "F.Cu" "F.Mask" "F.Paste")
			(net "CLK_100M_CPU1_CLK12_DP")
		)
		(pad "56" smd rect
			(at -3.800094 4.500118 270)
			(size 0.2794 1.6002)
			(layers "F.Cu" "F.Mask" "F.Paste")
			(net "NC_M2_0_NC17")
		)
		(pad "57" smd rect
			(at 3.750056 4.750054 270)
			(size 0.2794 1.6002)
			(layers "F.Cu" "F.Mask" "F.Paste")
			(net "GND")
		)
		(pad "58" smd rect
			(at -3.800094 4.99999 270)
			(size 0.2794 1.6002)
			(layers "F.Cu" "F.Mask" "F.Paste")
			(net "NC_M2_0_NC18")
		)
		(pad "67" smd rect
			(at 3.750056 7.249922 270)
			(size 0.2794 1.6002)
			(layers "F.Cu" "F.Mask" "F.Paste")
			(net "NC_M2_0_NC19")
		)
		(pad "68" smd rect
			(at -3.800094 7.500112 270)
			(size 0.2794 1.6002)
			(layers "F.Cu" "F.Mask" "F.Paste")
			(net "NC_M2_0_SUSCLK")
		)
		(pad "69" smd rect
			(at 3.750056 7.750048 270)
			(size 0.2794 1.6002)
			(layers "F.Cu" "F.Mask" "F.Paste")
			(net "FM_M2_SSD_0_PEDET")
		)
		(pad "70" smd rect
			(at -3.800094 7.999984 270)
			(size 0.2794 1.6002)
			(layers "F.Cu" "F.Mask" "F.Paste")
			(net "P3V3_M2_0")
		)
		(pad "71" smd rect
			(at 3.750056 8.24992 270)
			(size 0.2794 1.6002)
			(layers "F.Cu" "F.Mask" "F.Paste")
			(net "GND")
		)
		(pad "72" smd rect
			(at -3.800094 8.50011 270)
			(size 0.2794 1.6002)
			(layers "F.Cu" "F.Mask" "F.Paste")
			(net "P3V3_M2_0")
		)
		(pad "73" smd rect
			(at 3.750056 8.750046 270)
			(size 0.2794 1.6002)
			(layers "F.Cu" "F.Mask" "F.Paste")
			(net "GND")
		)
		(pad "74" smd rect
			(at -3.800094 8.999982 270)
			(size 0.2794 1.6002)
			(layers "F.Cu" "F.Mask" "F.Paste")
			(net "P3V3_M2_0")
		)
		(pad "75" smd rect
			(at 3.750056 9.249918 270)
			(size 0.2794 1.6002)
			(layers "F.Cu" "F.Mask" "F.Paste")
			(net "GND")
		)
		(pad "G1" smd rect
			(at 2.975102 -10.349992 270)
			(size 1.2446 2.794)
			(layers "F.Cu" "F.Mask" "F.Paste")
			(net "GND")
		)
		(pad "G2" smd rect
			(at 2.975102 10.349992 270)
			(size 1.2446 2.794)
			(layers "F.Cu" "F.Mask" "F.Paste")
			(net "GND")
		)
	)
)
